# T6G (Grand Teton) — schematic netlist excerpt (pin names and nets, part order shuffled) for the footprints in the layout excerpt that follows; sources: Cadence DE-HDL packaged netlist, KiCad conversion of 04192023_DAF0TMB3IC0_F0TG_MB_C_brd_V02_OCP.brd

R5055  Q_RES  10K 5% CHIP  pkg 0402LF  page 27 : A = P1V5_BAT ; B = CPU0_RTC_LDO_SELECT
PC98  Q_CAPP  220UF 4V 20% SPCAP  pkg SMLF  page 201 : A = PVDDCR_CPU1_P0 ; B = GND

(kicad_pcb
	(version 20260206)
	(generator "pcbnew")
	(generator_version "10.0")
	(general
		(thickness 1.6)
		(legacy_teardrops no)
	)
	(paper "A4")
	(title_block
		(title "04192023_DAF0TMB3IC0_F0TG_MB_C_brd_V02_OCP.brd")
		(comment 1 "Grand Teton / footprints 5463-5464 of 8354")
	)
	(layers
		(0 "F.Cu" signal "TOP")
		(4 "In1.Cu" signal "GND")
		(6 "In2.Cu" signal "IN1")
		(8 "In3.Cu" signal "GND1")
		(10 "In4.Cu" signal "IN2")
		(12 "In5.Cu" signal "GND2")
		(14 "In6.Cu" signal "IN3")
		(16 "In7.Cu" signal "GND3")
		(18 "In8.Cu" signal "VCC")
		(20 "In9.Cu" signal "VCC1")
		(22 "In10.Cu" signal "GND4")
		(24 "In11.Cu" signal "IN4")
		(26 "In12.Cu" signal "GND5")
		(28 "In13.Cu" signal "IN5")
		(30 "In14.Cu" signal "GND6")
		(32 "In15.Cu" signal "IN6")
		(34 "In16.Cu" signal "GND7")
		(2 "B.Cu" signal "BOTTOM")
		(9 "F.Adhes" user "F.Adhesive")
		(11 "B.Adhes" user "B.Adhesive")
		(13 "F.Paste" user "Package Geometry/Pastemask Top")
		(15 "B.Paste" user "Package Geometry/Pastemask Bottom")
		(5 "F.SilkS" user "Ref Des/Silkscreen Top")
		(7 "B.SilkS" user "Ref Des/Silkscreen Bottom")
		(1 "F.Mask" user "Board Geometry/Soldermask Top")
		(3 "B.Mask" user "Board Geometry/Soldermask Bottom")
		(17 "Dwgs.User" user "User.Drawings")
		(19 "Cmts.User" user "User.Comments")
		(21 "Eco1.User" user "User.Eco1")
		(23 "Eco2.User" user "User.Eco2")
		(25 "Edge.Cuts" user "Board Geometry/Outline")
		(27 "Margin" user)
		(31 "F.CrtYd" user "Package Geometry/Place Bound Top")
		(29 "B.CrtYd" user "Package Geometry/Place Bound Bottom")
		(35 "F.Fab" user "Ref Des/Assembly Top")
		(33 "B.Fab" user "Ref Des/Assembly Bottom")
	)
	(footprint ""
		(layer "B.Cu")
		(at 343.43467 -328.212704 -90)
		(property "Reference" "PC98"
			(at 9.746996 -0.271526 270)
			(unlocked yes)
			(layer "B.SilkS")
			(effects
				(font
					(size 0.7874 0.5842)
					(thickness 0.1524)
				)
				(justify left mirror)
			)
		)
		(property "Value" ""
			(at 0 0 90)
			(layer "B.Fab")
			(effects
				(font
					(size 1.27 1.27)
				)
				(justify mirror)
			)
		)
		(duplicate_pad_numbers_are_jumpers no)
		(fp_line
			(start -4.533392 2.249932)
			(end 4.533392 2.249932)
			(stroke
				(width 0.1524)
				(type default)
			)
			(layer "B.SilkS")
		)
		(fp_line
			(start 4.533392 2.249932)
			(end 4.533392 -2.249932)
			(stroke
				(width 0.1524)
				(type default)
			)
			(layer "B.SilkS")
		)
		(fp_line
			(start -4.533392 -2.249932)
			(end -4.533392 2.249932)
			(stroke
				(width 0.1524)
				(type default)
			)
			(layer "B.SilkS")
		)
		(fp_line
			(start 4.533392 -2.249932)
			(end -4.533392 -2.249932)
			(stroke
				(width 0.1524)
				(type default)
			)
			(layer "B.SilkS")
		)
		(fp_rect
			(start 5.39242 2.326132)
			(end 4.533392 -2.326132)
			(stroke
				(width 0)
				(type default)
			)
			(fill yes)
			(layer "B.SilkS")
		)
		(fp_line
			(start -3.750056 2.249932)
			(end 3.750056 2.249932)
			(stroke
				(width 0.1)
				(type default)
			)
			(layer "B.Fab")
		)
		(fp_line
			(start 3.750056 2.249932)
			(end 3.750056 -2.249932)
			(stroke
				(width 0.1)
				(type default)
			)
			(layer "B.Fab")
		)
		(fp_line
			(start -3.750056 -2.249932)
			(end -3.750056 2.249932)
			(stroke
				(width 0.1)
				(type default)
			)
			(layer "B.Fab")
		)
		(fp_line
			(start 3.750056 -2.249932)
			(end -3.750056 -2.249932)
			(stroke
				(width 0.1)
				(type default)
			)
			(layer "B.Fab")
		)
		(fp_text user "+"
			(at 6.322314 0.786384 180)
			(unlocked yes)
			(layer "B.SilkS")
			(effects
				(font
					(size 1.905 1.4224)
					(thickness 0.1524)
				)
				(justify left mirror)
			)
		)
		(fp_text user "-"
			(at -4.8514 -0.14605 270)
			(unlocked yes)
			(layer "B.SilkS")
			(effects
				(font
					(size 1.905 1.4224)
					(thickness 0.1524)
				)
				(justify left mirror)
			)
		)
		(fp_text user "+"
			(at 6.322314 0.786384 180)
			(unlocked yes)
			(layer "B.Fab")
			(effects
				(font
					(size 1.905 1.4224)
					(thickness 0.1524)
				)
				(justify left mirror)
			)
		)
		(fp_text user "-"
			(at -4.8514 -0.14605 270)
			(unlocked yes)
			(layer "B.Fab")
			(effects
				(font
					(size 1.905 1.4224)
					(thickness 0.1524)
				)
				(justify left mirror)
			)
		)
		(pad "1" smd rect
			(at 3.199892 0 90)
			(size 2.413 2.8194)
			(layers "B.Cu" "B.Mask" "B.Paste")
			(net "PVDDCR_CPU1_P0")
		)
		(pad "2" smd rect
			(at -3.199892 0 90)
			(size 2.413 2.8194)
			(layers "B.Cu" "B.Mask" "B.Paste")
			(net "GND")
		)
	)
	(footprint ""
		(layer "B.Cu")
		(at 408.597608 -329.987402 90)
		(property "Reference" "R5055"
			(at 0 0 90)
			(layer "B.SilkS")
			(hide yes)
			(effects
				(font
					(size 1.27 1.27)
				)
				(justify mirror)
			)
		)
		(property "Value" ""
			(at 0 0 90)
			(layer "B.Fab")
			(effects
				(font
					(size 1.27 1.27)
				)
				(justify mirror)
			)
		)
		(duplicate_pad_numbers_are_jumpers no)
		(fp_line
			(start 0.7874 -0.4064)
			(end -0.7874 -0.4064)
			(stroke
				(width 0.1524)
				(type default)
			)
			(layer "B.SilkS")
		)
		(fp_line
			(start -0.7874 -0.4064)
			(end -0.7874 0.4064)
			(stroke
				(width 0.1524)
				(type default)
			)
			(layer "B.SilkS")
		)
		(fp_line
			(start 0.7874 0.4064)
			(end 0.7874 -0.4064)
			(stroke
				(width 0.1524)
				(type default)
			)
			(layer "B.SilkS")
		)
		(fp_line
			(start -0.7874 0.4064)
			(end 0.7874 0.4064)
			(stroke
				(width 0.1524)
				(type default)
			)
			(layer "B.SilkS")
		)
		(fp_line
			(start 0.67945 -0.305054)
			(end 0.12065 -0.305054)
			(stroke
				(width 0.1)
				(type default)
			)
			(layer "B.Fab")
		)
		(fp_line
			(start 0.12065 -0.305054)
			(end 0.12065 -0.2794)
			(stroke
				(width 0.1)
				(type default)
			)
			(layer "B.Fab")
		)
		(fp_line
			(start -0.12065 -0.3048)
			(end -0.67945 -0.3048)
			(stroke
				(width 0.1)
				(type default)
			)
			(layer "B.Fab")
		)
		(fp_line
			(start -0.67945 -0.3048)
			(end -0.67945 0.3048)
			(stroke
				(width 0.1)
				(type default)
			)
			(layer "B.Fab")
		)
		(fp_line
			(start 0.12065 -0.2794)
			(end -0.12065 -0.2794)
			(stroke
				(width 0.1)
				(type default)
			)
			(layer "B.Fab")
		)
		(fp_line
			(start -0.12065 -0.2794)
			(end -0.12065 -0.3048)
			(stroke
				(width 0.1)
				(type default)
			)
			(layer "B.Fab")
		)
		(fp_line
			(start 0.12065 0.2794)
			(end 0.12065 0.3048)
			(stroke
				(width 0.1)
				(type default)
			)
			(layer "B.Fab")
		)
		(fp_line
			(start -0.120396 0.2794)
			(end 0.12065 0.2794)
			(stroke
				(width 0.1)
				(type default)
			)
			(layer "B.Fab")
		)
		(fp_line
			(start 0.67945 0.3048)
			(end 0.67945 -0.305054)
			(stroke
				(width 0.1)
				(type default)
			)
			(layer "B.Fab")
		)
		(fp_line
			(start 0.12065 0.3048)
			(end 0.67945 0.3048)
			(stroke
				(width 0.1)
				(type default)
			)
			(layer "B.Fab")
		)
		(fp_line
			(start -0.120396 0.3048)
			(end -0.120396 0.2794)
			(stroke
				(width 0.1)
				(type default)
			)
			(layer "B.Fab")
		)
		(fp_line
			(start -0.67945 0.3048)
			(end -0.120396 0.3048)
			(stroke
				(width 0.1)
				(type default)
			)
			(layer "B.Fab")
		)
		(pad "1" smd circle
			(at 0.40005 0 270)
			(size 0 0)
			(layers "B.Cu" "B.Mask" "B.Paste")
			(net "P1V5_BAT")
		)
		(pad "2" smd circle
			(at -0.40005 0 270)
			(size 0 0)
			(layers "B.Cu" "B.Mask" "B.Paste")
			(net "CPU0_RTC_LDO_SELECT")
		)
	)
)
